# T6G (Grand Teton) — schematic netlist excerpt (pin names and nets, part order shuffled) for the footprints in the layout excerpt that follows; sources: Cadence DE-HDL packaged netlist, KiCad conversion of 04192023_DAF0TMB3IC0_F0TG_MB_C_brd_V02_OCP.brd

R6238  Q_RES  0 5% EMPTY  pkg 0402LF  page 267 : A = A_HSC_LOW_DRAIN ; B = HSC_D_OC
PC6811  Q_CAPP  470UF 2.5V 20% SPCAP  pkg SMLF  page 363 : A = P0V9_CPU0_RT_2D ; B = GND

(kicad_pcb
	(version 20260206)
	(generator "pcbnew")
	(generator_version "10.0")
	(general
		(thickness 1.6)
		(legacy_teardrops no)
	)
	(paper "A4")
	(title_block
		(title "04192023_DAF0TMB3IC0_F0TG_MB_C_brd_V02_OCP.brd")
		(comment 1 "Grand Teton / footprints 6778-6779 of 8354")
	)
	(layers
		(0 "F.Cu" signal "TOP")
		(4 "In1.Cu" signal "GND")
		(6 "In2.Cu" signal "IN1")
		(8 "In3.Cu" signal "GND1")
		(10 "In4.Cu" signal "IN2")
		(12 "In5.Cu" signal "GND2")
		(14 "In6.Cu" signal "IN3")
		(16 "In7.Cu" signal "GND3")
		(18 "In8.Cu" signal "VCC")
		(20 "In9.Cu" signal "VCC1")
		(22 "In10.Cu" signal "GND4")
		(24 "In11.Cu" signal "IN4")
		(26 "In12.Cu" signal "GND5")
		(28 "In13.Cu" signal "IN5")
		(30 "In14.Cu" signal "GND6")
		(32 "In15.Cu" signal "IN6")
		(34 "In16.Cu" signal "GND7")
		(2 "B.Cu" signal "BOTTOM")
		(9 "F.Adhes" user "F.Adhesive")
		(11 "B.Adhes" user "B.Adhesive")
		(13 "F.Paste" user "Package Geometry/Pastemask Top")
		(15 "B.Paste" user "Package Geometry/Pastemask Bottom")
		(5 "F.SilkS" user "Ref Des/Silkscreen Top")
		(7 "B.SilkS" user "Ref Des/Silkscreen Bottom")
		(1 "F.Mask" user "Board Geometry/Soldermask Top")
		(3 "B.Mask" user "Board Geometry/Soldermask Bottom")
		(17 "Dwgs.User" user "User.Drawings")
		(19 "Cmts.User" user "User.Comments")
		(21 "Eco1.User" user "User.Eco1")
		(23 "Eco2.User" user "User.Eco2")
		(25 "Edge.Cuts" user "Board Geometry/Outline")
		(27 "Margin" user)
		(31 "F.CrtYd" user "Package Geometry/Place Bound Top")
		(29 "B.CrtYd" user "Package Geometry/Place Bound Bottom")
		(35 "F.Fab" user "Ref Des/Assembly Top")
		(33 "B.Fab" user "Ref Des/Assembly Bottom")
	)
	(footprint ""
		(layer "B.Cu")
		(at 446.579752 -390.405874 -90)
		(property "Reference" "PC6811"
			(at -0.754126 2.995422 270)
			(unlocked yes)
			(layer "B.SilkS")
			(effects
				(font
					(size 0.7874 0.5842)
					(thickness 0.1524)
				)
				(justify left mirror)
			)
		)
		(property "Value" ""
			(at 0 0 90)
			(layer "B.Fab")
			(effects
				(font
					(size 1.27 1.27)
				)
				(justify mirror)
			)
		)
		(duplicate_pad_numbers_are_jumpers no)
		(fp_line
			(start 4.83108 2.150364)
			(end 4.447794 2.149348)
			(stroke
				(width 0.1524)
				(type default)
			)
			(layer "B.SilkS")
		)
		(fp_line
			(start -4.53898 2.15011)
			(end 4.53898 2.15011)
			(stroke
				(width 0.1524)
				(type default)
			)
			(layer "B.SilkS")
		)
		(fp_line
			(start 4.53898 2.15011)
			(end 4.53898 -2.15011)
			(stroke
				(width 0.1524)
				(type default)
			)
			(layer "B.SilkS")
		)
		(fp_line
			(start -4.53898 -2.15011)
			(end -4.53898 2.15011)
			(stroke
				(width 0.1524)
				(type default)
			)
			(layer "B.SilkS")
		)
		(fp_line
			(start 4.53898 -2.15011)
			(end -4.53898 -2.15011)
			(stroke
				(width 0.1524)
				(type default)
			)
			(layer "B.SilkS")
		)
		(fp_line
			(start 4.53898 -2.150618)
			(end 4.539742 2.152142)
			(stroke
				(width 0.1524)
				(type default)
			)
			(layer "B.SilkS")
		)
		(fp_line
			(start 4.69138 -2.150618)
			(end 4.692396 2.161032)
			(stroke
				(width 0.1524)
				(type default)
			)
			(layer "B.SilkS")
		)
		(fp_line
			(start 4.84378 -2.150618)
			(end 4.842256 2.163064)
			(stroke
				(width 0.1524)
				(type default)
			)
			(layer "B.SilkS")
		)
		(fp_line
			(start 4.84378 -2.150618)
			(end 4.53898 -2.150618)
			(stroke
				(width 0.1524)
				(type default)
			)
			(layer "B.SilkS")
		)
		(fp_line
			(start -3.64998 2.15011)
			(end 3.64998 2.15011)
			(stroke
				(width 0.1)
				(type default)
			)
			(layer "B.Fab")
		)
		(fp_line
			(start 3.64998 2.15011)
			(end 3.64998 -2.15011)
			(stroke
				(width 0.1)
				(type default)
			)
			(layer "B.Fab")
		)
		(fp_line
			(start -3.64998 -2.15011)
			(end -3.64998 2.15011)
			(stroke
				(width 0.1)
				(type default)
			)
			(layer "B.Fab")
		)
		(fp_line
			(start 3.64998 -2.15011)
			(end -3.64998 -2.15011)
			(stroke
				(width 0.1)
				(type default)
			)
			(layer "B.Fab")
		)
		(fp_text user "+"
			(at 6.329172 -0.680212 270)
			(unlocked yes)
			(layer "B.SilkS")
			(effects
				(font
					(size 1.905 1.4224)
					(thickness 0.1524)
				)
				(justify left mirror)
			)
		)
		(fp_text user "-"
			(at -4.731512 -3.37566 270)
			(unlocked yes)
			(layer "B.SilkS")
			(effects
				(font
					(size 1.905 1.4224)
					(thickness 0.1524)
				)
				(justify left mirror)
			)
		)
		(fp_text user "-"
			(at -4.313174 -0.094488 270)
			(unlocked yes)
			(layer "B.Fab")
			(effects
				(font
					(size 1.905 1.4224)
					(thickness 0.1524)
				)
				(justify left mirror)
			)
		)
		(fp_text user "+"
			(at 6.214872 -0.337058 270)
			(unlocked yes)
			(layer "B.Fab")
			(effects
				(font
					(size 1.905 1.4224)
					(thickness 0.1524)
				)
				(justify left mirror)
			)
		)
		(pad "1" smd rect
			(at 3.199892 0 90)
			(size 2.413 2.8194)
			(layers "B.Cu" "B.Mask" "B.Paste")
			(net "P0V9_CPU0_RT_2D")
		)
		(pad "2" smd rect
			(at -3.199892 0 90)
			(size 2.413 2.8194)
			(layers "B.Cu" "B.Mask" "B.Paste")
			(net "GND")
		)
	)
	(footprint ""
		(layer "B.Cu")
		(at 175.50638 -422.234614 180)
		(property "Reference" "R6238"
			(at 0 0 0)
			(layer "B.SilkS")
			(hide yes)
			(effects
				(font
					(size 1.27 1.27)
				)
				(justify mirror)
			)
		)
		(property "Value" ""
			(at 0 0 0)
			(layer "B.Fab")
			(effects
				(font
					(size 1.27 1.27)
				)
				(justify mirror)
			)
		)
		(duplicate_pad_numbers_are_jumpers no)
		(fp_line
			(start 0.7874 0.4064)
			(end 0.7874 -0.4064)
			(stroke
				(width 0.1524)
				(type default)
			)
			(layer "B.SilkS")
		)
		(fp_line
			(start 0.7874 -0.4064)
			(end -0.7874 -0.4064)
			(stroke
				(width 0.1524)
				(type default)
			)
			(layer "B.SilkS")
		)
		(fp_line
			(start -0.7874 0.4064)
			(end 0.7874 0.4064)
			(stroke
				(width 0.1524)
				(type default)
			)
			(layer "B.SilkS")
		)
		(fp_line
			(start -0.7874 -0.4064)
			(end -0.7874 0.4064)
			(stroke
				(width 0.1524)
				(type default)
			)
			(layer "B.SilkS")
		)
		(fp_line
			(start 0.67945 0.3048)
			(end 0.67945 -0.305054)
			(stroke
				(width 0.1)
				(type default)
			)
			(layer "B.Fab")
		)
		(fp_line
			(start 0.67945 -0.305054)
			(end 0.12065 -0.305054)
			(stroke
				(width 0.1)
				(type default)
			)
			(layer "B.Fab")
		)
		(fp_line
			(start 0.12065 0.3048)
			(end 0.67945 0.3048)
			(stroke
				(width 0.1)
				(type default)
			)
			(layer "B.Fab")
		)
		(fp_line
			(start 0.12065 0.2794)
			(end 0.12065 0.3048)
			(stroke
				(width 0.1)
				(type default)
			)
			(layer "B.Fab")
		)
		(fp_line
			(start 0.12065 -0.2794)
			(end -0.12065 -0.2794)
			(stroke
				(width 0.1)
				(type default)
			)
			(layer "B.Fab")
		)
		(fp_line
			(start 0.12065 -0.305054)
			(end 0.12065 -0.2794)
			(stroke
				(width 0.1)
				(type default)
			)
			(layer "B.Fab")
		)
		(fp_line
			(start -0.120396 0.3048)
			(end -0.120396 0.2794)
			(stroke
				(width 0.1)
				(type default)
			)
			(layer "B.Fab")
		)
		(fp_line
			(start -0.120396 0.2794)
			(end 0.12065 0.2794)
			(stroke
				(width 0.1)
				(type default)
			)
			(layer "B.Fab")
		)
		(fp_line
			(start -0.12065 -0.2794)
			(end -0.12065 -0.3048)
			(stroke
				(width 0.1)
				(type default)
			)
			(layer "B.Fab")
		)
		(fp_line
			(start -0.12065 -0.3048)
			(end -0.67945 -0.3048)
			(stroke
				(width 0.1)
				(type default)
			)
			(layer "B.Fab")
		)
		(fp_line
			(start -0.67945 0.3048)
			(end -0.120396 0.3048)
			(stroke
				(width 0.1)
				(type default)
			)
			(layer "B.Fab")
		)
		(fp_line
			(start -0.67945 -0.3048)
			(end -0.67945 0.3048)
			(stroke
				(width 0.1)
				(type default)
			)
			(layer "B.Fab")
		)
		(pad "1" smd circle
			(at 0.40005 0)
			(size 0 0)
			(layers "B.Cu" "B.Mask" "B.Paste")
			(net "A_HSC_LOW_DRAIN")
		)
		(pad "2" smd circle
			(at -0.40005 0)
			(size 0 0)
			(layers "B.Cu" "B.Mask" "B.Paste")
			(net "HSC_D_OC")
		)
	)
)
